# T6G (Grand Teton) — schematic netlist excerpt (pin names and nets, part order shuffled) for the footprints in the layout excerpt that follows; sources: Cadence DE-HDL packaged netlist, KiCad conversion of 04192023_DAF0TMB3IC0_F0TG_MB_C_brd_V02_OCP.brd

FS1  Q_FUSE  20A/125V IC  pkg SMLF  page 268 : \1\ = P12V_PSU ; \2\ = P12V_PSU_FUSE
C768  Q_CAP_DIFFBUS  DIFF BUS_0.22UF 6.3V 20% X6S  pkg C0201  page 66 : \1\ = P5E_CPU1_P2_TX_C_DN<2> ; \2\ = P5E_CPU1_P2_TX_DN<2>
R6088  Q_RES  10K 1% EMPTY  pkg 0402LF  page 217 : A = PVDDIO_P1_EN_R ; B = GND

(kicad_pcb
	(version 20260206)
	(generator "pcbnew")
	(generator_version "10.0")
	(general
		(thickness 1.6)
		(legacy_teardrops no)
	)
	(paper "A4")
	(title_block
		(title "04192023_DAF0TMB3IC0_F0TG_MB_C_brd_V02_OCP.brd")
		(comment 1 "Grand Teton / footprints 891-893 of 8354")
	)
	(layers
		(0 "F.Cu" signal "TOP")
		(4 "In1.Cu" signal "GND")
		(6 "In2.Cu" signal "IN1")
		(8 "In3.Cu" signal "GND1")
		(10 "In4.Cu" signal "IN2")
		(12 "In5.Cu" signal "GND2")
		(14 "In6.Cu" signal "IN3")
		(16 "In7.Cu" signal "GND3")
		(18 "In8.Cu" signal "VCC")
		(20 "In9.Cu" signal "VCC1")
		(22 "In10.Cu" signal "GND4")
		(24 "In11.Cu" signal "IN4")
		(26 "In12.Cu" signal "GND5")
		(28 "In13.Cu" signal "IN5")
		(30 "In14.Cu" signal "GND6")
		(32 "In15.Cu" signal "IN6")
		(34 "In16.Cu" signal "GND7")
		(2 "B.Cu" signal "BOTTOM")
		(9 "F.Adhes" user "F.Adhesive")
		(11 "B.Adhes" user "B.Adhesive")
		(13 "F.Paste" user "Package Geometry/Pastemask Top")
		(15 "B.Paste" user "Package Geometry/Pastemask Bottom")
		(5 "F.SilkS" user "Ref Des/Silkscreen Top")
		(7 "B.SilkS" user "Ref Des/Silkscreen Bottom")
		(1 "F.Mask" user "Board Geometry/Soldermask Top")
		(3 "B.Mask" user "Board Geometry/Soldermask Bottom")
		(17 "Dwgs.User" user "User.Drawings")
		(19 "Cmts.User" user "User.Comments")
		(21 "Eco1.User" user "User.Eco1")
		(23 "Eco2.User" user "User.Eco2")
		(25 "Edge.Cuts" user "Board Geometry/Outline")
		(27 "Margin" user)
		(31 "F.CrtYd" user "Package Geometry/Place Bound Top")
		(29 "B.CrtYd" user "Package Geometry/Place Bound Bottom")
		(35 "F.Fab" user "Ref Des/Assembly Top")
		(33 "B.Fab" user "Ref Des/Assembly Bottom")
	)
	(footprint ""
		(layer "F.Cu")
		(at 18.384012 -358.30637 -90)
		(property "Reference" "R6088"
			(at 0 0 270)
			(layer "F.SilkS")
			(hide yes)
			(effects
				(font
					(size 1.27 1.27)
				)
			)
		)
		(property "Value" ""
			(at 0 0 270)
			(layer "F.Fab")
			(effects
				(font
					(size 1.27 1.27)
				)
			)
		)
		(duplicate_pad_numbers_are_jumpers no)
		(fp_line
			(start -0.7874 0.4064)
			(end -0.7874 -0.4064)
			(stroke
				(width 0.1524)
				(type default)
			)
			(layer "F.SilkS")
		)
		(fp_line
			(start 0.7874 0.4064)
			(end -0.7874 0.4064)
			(stroke
				(width 0.1524)
				(type default)
			)
			(layer "F.SilkS")
		)
		(fp_line
			(start -0.7874 -0.4064)
			(end 0.7874 -0.4064)
			(stroke
				(width 0.1524)
				(type default)
			)
			(layer "F.SilkS")
		)
		(fp_line
			(start 0.7874 -0.4064)
			(end 0.7874 0.4064)
			(stroke
				(width 0.1524)
				(type default)
			)
			(layer "F.SilkS")
		)
		(fp_line
			(start -0.67945 0.3048)
			(end -0.67945 -0.305054)
			(stroke
				(width 0.1)
				(type default)
			)
			(layer "F.Fab")
		)
		(fp_line
			(start -0.12065 0.3048)
			(end -0.67945 0.3048)
			(stroke
				(width 0.1)
				(type default)
			)
			(layer "F.Fab")
		)
		(fp_line
			(start 0.120396 0.3048)
			(end 0.120396 0.2794)
			(stroke
				(width 0.1)
				(type default)
			)
			(layer "F.Fab")
		)
		(fp_line
			(start 0.67945 0.3048)
			(end 0.120396 0.3048)
			(stroke
				(width 0.1)
				(type default)
			)
			(layer "F.Fab")
		)
		(fp_line
			(start -0.12065 0.2794)
			(end -0.12065 0.3048)
			(stroke
				(width 0.1)
				(type default)
			)
			(layer "F.Fab")
		)
		(fp_line
			(start 0.120396 0.2794)
			(end -0.12065 0.2794)
			(stroke
				(width 0.1)
				(type default)
			)
			(layer "F.Fab")
		)
		(fp_line
			(start -0.12065 -0.2794)
			(end 0.12065 -0.2794)
			(stroke
				(width 0.1)
				(type default)
			)
			(layer "F.Fab")
		)
		(fp_line
			(start 0.12065 -0.2794)
			(end 0.12065 -0.3048)
			(stroke
				(width 0.1)
				(type default)
			)
			(layer "F.Fab")
		)
		(fp_line
			(start 0.12065 -0.3048)
			(end 0.67945 -0.3048)
			(stroke
				(width 0.1)
				(type default)
			)
			(layer "F.Fab")
		)
		(fp_line
			(start 0.67945 -0.3048)
			(end 0.67945 0.3048)
			(stroke
				(width 0.1)
				(type default)
			)
			(layer "F.Fab")
		)
		(fp_line
			(start -0.67945 -0.305054)
			(end -0.12065 -0.305054)
			(stroke
				(width 0.1)
				(type default)
			)
			(layer "F.Fab")
		)
		(fp_line
			(start -0.12065 -0.305054)
			(end -0.12065 -0.2794)
			(stroke
				(width 0.1)
				(type default)
			)
			(layer "F.Fab")
		)
		(pad "1" smd circle
			(at -0.40005 0 270)
			(size 0 0)
			(layers "F.Cu" "F.Mask" "F.Paste")
			(net "PVDDIO_P1_EN_R")
		)
		(pad "2" smd circle
			(at 0.40005 0 270)
			(size 0 0)
			(layers "F.Cu" "F.Mask" "F.Paste")
			(net "GND")
		)
	)
	(footprint ""
		(layer "F.Cu")
		(at 143.531844 -373.03583 -90)
		(property "Reference" "C768"
			(at 0 0 270)
			(layer "F.SilkS")
			(hide yes)
			(effects
				(font
					(size 1.27 1.27)
				)
			)
		)
		(property "Value" ""
			(at 0 0 270)
			(layer "F.Fab")
			(effects
				(font
					(size 1.27 1.27)
				)
			)
		)
		(duplicate_pad_numbers_are_jumpers no)
		(fp_line
			(start -0.299974 0.150114)
			(end -0.299974 -0.150114)
			(stroke
				(width 0.1)
				(type default)
			)
			(layer "F.Fab")
		)
		(fp_line
			(start 0.299974 0.150114)
			(end -0.299974 0.150114)
			(stroke
				(width 0.1)
				(type default)
			)
			(layer "F.Fab")
		)
		(fp_line
			(start -0.299974 -0.150114)
			(end 0.299974 -0.150114)
			(stroke
				(width 0.1)
				(type default)
			)
			(layer "F.Fab")
		)
		(fp_line
			(start 0.299974 -0.150114)
			(end 0.299974 0.150114)
			(stroke
				(width 0.1)
				(type default)
			)
			(layer "F.Fab")
		)
		(pad "1" smd rect
			(at -0.2667 0 270)
			(size 0.3048 0.381)
			(layers "F.Cu" "F.Mask" "F.Paste")
			(net "P5E_CPU1_P2_TX_C_DN<2>")
		)
		(pad "2" smd rect
			(at 0.2667 0 270)
			(size 0.3048 0.381)
			(layers "F.Cu" "F.Mask" "F.Paste")
			(net "P5E_CPU1_P2_TX_DN<2>")
		)
	)
	(footprint ""
		(layer "F.Cu")
		(at 236.003338 -416.997642)
		(property "Reference" "FS1"
			(at -6.4262 -2.64033 0)
			(unlocked yes)
			(layer "F.SilkS")
			(effects
				(font
					(size 0.7874 0.5842)
					(thickness 0.1524)
				)
				(justify left)
			)
		)
		(property "Value" ""
			(at 0 0 0)
			(layer "F.Fab")
			(effects
				(font
					(size 1.27 1.27)
				)
			)
		)
		(duplicate_pad_numbers_are_jumpers no)
		(fp_line
			(start -6.427724 -1.8415)
			(end -6.427724 1.8415)
			(stroke
				(width 0.1524)
				(type default)
			)
			(layer "F.SilkS")
		)
		(fp_line
			(start -6.427724 1.8415)
			(end 6.427724 1.8415)
			(stroke
				(width 0.1524)
				(type default)
			)
			(layer "F.SilkS")
		)
		(fp_line
			(start 6.427724 -1.8415)
			(end -6.427724 -1.8415)
			(stroke
				(width 0.1524)
				(type default)
			)
			(layer "F.SilkS")
		)
		(fp_line
			(start 6.427724 1.8415)
			(end 6.427724 -1.8415)
			(stroke
				(width 0.1524)
				(type default)
			)
			(layer "F.SilkS")
		)
		(fp_line
			(start -5.225034 -1.610106)
			(end 5.225034 -1.610106)
			(stroke
				(width 0.1)
				(type default)
			)
			(layer "F.Fab")
		)
		(fp_line
			(start -5.225034 1.610106)
			(end -5.225034 -1.610106)
			(stroke
				(width 0.1)
				(type default)
			)
			(layer "F.Fab")
		)
		(fp_line
			(start 5.225034 -1.610106)
			(end 5.225034 1.610106)
			(stroke
				(width 0.1)
				(type default)
			)
			(layer "F.Fab")
		)
		(fp_line
			(start 5.225034 1.610106)
			(end -5.225034 1.610106)
			(stroke
				(width 0.1)
				(type default)
			)
			(layer "F.Fab")
		)
		(pad "1" smd rect
			(at -4.675124 0)
			(size 3.2512 3.429)
			(layers "F.Cu" "F.Mask" "F.Paste")
			(net "P12V_PSU")
		)
		(pad "2" smd rect
			(at 4.675124 0)
			(size 3.2512 3.429)
			(layers "F.Cu" "F.Mask" "F.Paste")
			(net "P12V_PSU_FUSE")
		)
	)
)
